FILE_TYPE = CONNECTIVITY;
{Allegro Design Entry HDL 16.6-p007 (v16-6-112F) 10/10/2012}
"PAGE_NUMBER" = 159;
0"NC";
1"P3V3_STBY\g";
2"P3V3_STBY\g";
3"P3V3_STBY\g";
4"P3V3_STBY\g";
5"P3V3_STBY\g";
6"P3V3_STBY\g";
7"SMB_SMLINK0_STBY_LVC3_SCL";
8"SMB_SMLINK0_STBY_LVC3_SCL";
9"SMB_SMLINK0_STBY_LVC3_SDA";
10"SMB_VR_STBY_LVC3_SDA_R";
11"SMB_OCP_LAN_STBY_LVC3_SDA";
12"SMB_OCP_LAN_STBY_LVC3_SDA_R";
13"SMB_OCP_LAN_STBY_LVC3_SCL_R";
14"SMB_BMC_PMBUS_STBY_LVC3_SDA_R";
15"SMB_OCP_FRU_STBY_LVC3_SDA_R";
16"SMB_BMC_PMBUS_STBY_LVC3_SCL";
17"SMB_BMC_PMBUS_STBY_LVC3_SDA";
18"SMB_OCP_FRU_STBY_LVC3_SCL_R";
19"SMB_BMC_PMBUS_STBY_LVC3_SCL_R";
20"SMB_HOST_STBY_LVC3_SDA";
21"SMB_HOST_STBY_LVC3_SCL";
22"SMB_OCP_FRU_STBY_LVC3_SDA";
23"SMB_OCP_FRU_STBY_LVC3_SCL";
24"SMB_VR_STBY_LVC3_SDA";
25"SMB_OCP_LAN_STBY_LVC3_SCL";
26"SMB_OCP_LAN_STBY_LVC3_SCL";
27"SMB_SPRINGVILLE_STBY_LVC3_SDA";
28"SMB_SPRINGVILLE_STBY_LVC3_SCL";
29"SMB_VR_STBY_LVC3_SCL";
30"SMB_VR_STBY_LVC3_SCL_R";
31"SMB_OCP_LAN_STBY_LVC3_SDA";
32"SMB_SMLINK0_STBY_LVC3_SDA";
33"SMB_HOST_STBY_LVC3_SDA_R";
34"SMB_HOST_STBY_LVC3_SCL_R";
35"SMB_SMLINK0_STBY_LVC3_SCL_R";
36"SMB_SMLINK0_STBY_LVC3_SDA_R";
%"P3V3_STBY"
"1","(-3375,3200)","0","mstr_symbols","I209";
;
CDS_LIB"mstr_symbols"
SIZE"1B"
VOLTAGE"3.3V"
BODY_TYPE"PLUMBING"
HDL_POWER"P3V3_STBY";
"G\NAC"1;
%"RES"
"2","(-3375,2900)","0","mstr_discrete","I210";
;
CDS_SEC"1"
MATERIAL"EMPTY"
PART_NUMBER"G21796-311"
PACK_TYPE"0402"
TOLERANCE"1.0%"
WATTAGE"1/16W"
VALUE"2.26K"
LOCATION"R8G3"
SEC_TYPE"0402"
SEC"1"
BOM_COST"SM_CONTROLLER"
SKU"B"
ROOM"SMBUS"
CDS_LOCATION"R8G3"
CDS_LIB"mstr_discrete";
"A"
$PN"1"1;
"B"
$PN"2"13;
%"P3V3_STBY"
"1","(-3725,3200)","0","mstr_symbols","I211";
;
SIZE"1B"
CDS_LIB"mstr_symbols"
VOLTAGE"3.3V"
BODY_TYPE"PLUMBING"
HDL_POWER"P3V3_STBY";
"G\NAC"2;
%"RES"
"2","(-3725,2900)","0","mstr_discrete","I212";
;
CDS_SEC"1"
PACK_TYPE"0402"
WATTAGE"1/16W"
MATERIAL"EMPTY"
PART_NUMBER"G21796-311"
TOLERANCE"1.0%"
VALUE"2.26K"
LOCATION"R8G6"
SEC_TYPE"0402"
SEC"1"
SKU"B"
BOM_COST"SM_CONTROLLER"
ROOM"SMBUS"
CDS_LOCATION"R8G6"
CDS_LIB"mstr_discrete";
"A"
$PN"1"2;
"B"
$PN"2"12;
%"P3V3_STBY"
"1","(550,5125)","0","mstr_symbols","I213";
;
CDS_LIB"mstr_symbols"
SIZE"1B"
VOLTAGE"3.3V"
BODY_TYPE"PLUMBING"
HDL_POWER"P3V3_STBY";
"G\NAC"3;
%"RES"
"2","(550,4825)","0","mstr_discrete","I214";
;
CDS_SEC"1"
PART_NUMBER"G21796-311"
MATERIAL"CHIP"
WATTAGE"1/16W"
TOLERANCE"1.0%"
VALUE"2.26K"
LOCATION"R2U5"
PACK_TYPE"0402"
SEC_TYPE"0402"
SEC"1"
BOM_COST"SM_CONTROLLER"
SKU"B"
ROOM"SMBUS"
CDS_LOCATION"R2U5"
CDS_LIB"mstr_discrete";
"A"
$PN"1"3;
"B"
$PN"2"18;
%"P3V3_STBY"
"1","(200,5125)","0","mstr_symbols","I215";
;
SIZE"1B"
CDS_LIB"mstr_symbols"
VOLTAGE"3.3V"
BODY_TYPE"PLUMBING"
HDL_POWER"P3V3_STBY";
"G\NAC"4;
%"RES"
"2","(200,4825)","0","mstr_discrete","I216";
;
CDS_SEC"1"
PART_NUMBER"G21796-311"
PACK_TYPE"0402"
MATERIAL"CHIP"
WATTAGE"1/16W"
TOLERANCE"1.0%"
VALUE"2.26K"
LOCATION"R2U13"
SEC_TYPE"0402"
SEC"1"
BOM_COST"SM_CONTROLLER"
ROOM"SMBUS"
SKU"B"
CDS_LOCATION"R2U13"
CDS_LIB"mstr_discrete";
"A"
$PN"1"4;
"B"
$PN"2"15;
%"RES"
"1","(700,3375)","0","mstr_discrete","I218";
;
VALUE"20.0"
MATERIAL"CHIP"
LOCATION"R2U1"
PACK_TYPE"0402"
WATTAGE"1/16W"
PART_NUMBER"G21796-173"
TOLERANCE"1%"
CDS_SEC"1"
$SEC"1"
BOM_COST"SM_CONTROLLER"
ROOM"SMBUS"
CDS_LIB"mstr_discrete"
CDS_LOCATION"R2U1";
"B"
$PN"2"16;
"A"
$PN"1"19;
%"RES"
"1","(700,3550)","0","mstr_discrete","I219";
;
MATERIAL"CHIP"
LOCATION"R2T49"
WATTAGE"1/16W"
PACK_TYPE"0402"
VALUE"20.0"
PART_NUMBER"G21796-173"
TOLERANCE"1%"
BOM_COST"SM_CONTROLLER"
CDS_SEC"1"
$SEC"1"
CDS_LOCATION"R2T49"
ROOM"SMBUS"
CDS_LIB"mstr_discrete";
"B"
$PN"2"17;
"A"
$PN"1"14;
%"RES"
"1","(800,4275)","0","mstr_discrete","I220";
;
VALUE"20.0"
PACK_TYPE"0402"
PART_NUMBER"G21796-173"
TOLERANCE"1%"
MATERIAL"CHIP"
LOCATION"R2U7"
WATTAGE"1/16W"
CDS_LOCATION"R2U7"
ROOM"SMBUS"
BOM_COST"SM_CONTROLLER"
CDS_SEC"1"
$SEC"1"
CDS_LIB"mstr_discrete";
"B"
$PN"2"23;
"A"
$PN"1"18;
%"RES"
"1","(800,4450)","0","mstr_discrete","I221";
;
TOLERANCE"1%"
PART_NUMBER"G21796-173"
PACK_TYPE"0402"
LOCATION"R2U10"
MATERIAL"CHIP"
VALUE"20.0"
WATTAGE"1/16W"
ROOM"SMBUS"
CDS_LOCATION"R2U10"
BOM_COST"SM_CONTROLLER"
$SEC"1"
CDS_SEC"1"
CDS_LIB"mstr_discrete";
"B"
$PN"2"22;
"A"
$PN"1"15;
%"RES"
"1","(700,1600)","0","mstr_discrete","I222";
;
MATERIAL"CHIP"
LOCATION"R1U11"
PART_NUMBER"G21497-005"
WATTAGE"1/16W"
PACK_TYPE"0402"
VALUE"0.0"
TOLERANCE"5%"
CDS_SEC"1"
$SEC"1"
BOM_COST"SM_CONTROLLER"
ROOM"SMBUS"
CDS_LOCATION"R1U11"
CDS_LIB"mstr_discrete";
"B"
$PN"2"29;
"A"
$PN"1"30;
%"RES"
"1","(700,1775)","0","mstr_discrete","I223";
;
MATERIAL"CHIP"
LOCATION"R1U8"
TOLERANCE"5%"
PART_NUMBER"G21497-005"
VALUE"0.0"
WATTAGE"1/16W"
PACK_TYPE"0402"
BOM_COST"SM_CONTROLLER"
CDS_SEC"1"
$SEC"1"
CDS_LOCATION"R1U8"
ROOM"SMBUS"
CDS_LIB"mstr_discrete";
"B"
$PN"2"24;
"A"
$PN"1"10;
%"RES"
"1","(-3625,1575)","0","mstr_discrete","I224";
;
MATERIAL"CHIP"
TOLERANCE"1%"
PART_NUMBER"G21796-173"
VALUE"20.0"
WATTAGE"1/16W"
PACK_TYPE"0402"
LOCATION"R9G12"
CDS_SEC"1"
$SEC"1"
ROOM"SMBUS"
BOM_COST"SM_CONTROLLER"
CDS_LIB"mstr_discrete"
CDS_LOCATION"R9G12";
"B"
$PN"2"27;
"A"
$PN"1"11;
%"RES"
"1","(-3625,1450)","0","mstr_discrete","I225";
;
LOCATION"R1U20"
TOLERANCE"1%"
PART_NUMBER"G21796-173"
MATERIAL"CHIP"
VALUE"20.0"
WATTAGE"1/16W"
PACK_TYPE"0402"
CDS_SEC"1"
$SEC"1"
BOM_COST"SM_CONTROLLER"
ROOM"SMBUS"
CDS_LIB"mstr_discrete"
CDS_LOCATION"R1U20";
"B"
$PN"2"27;
"A"
$PN"1"9;
%"RES"
"1","(-3625,1325)","0","mstr_discrete","I226";
;
TOLERANCE"1%"
LOCATION"R1U19"
MATERIAL"CHIP"
PART_NUMBER"G21796-173"
PACK_TYPE"0402"
VALUE"20.0"
WATTAGE"1/16W"
CDS_SEC"1"
$SEC"1"
BOM_COST"SM_CONTROLLER"
ROOM"SMBUS"
CDS_LIB"mstr_discrete"
CDS_LOCATION"R1U19";
"B"
$PN"2"28;
"A"
$PN"1"8;
%"RES"
"1","(-3625,1200)","0","mstr_discrete","I227";
;
TOLERANCE"1%"
LOCATION"R9G13"
MATERIAL"CHIP"
PART_NUMBER"G21796-173"
VALUE"20.0"
PACK_TYPE"0402"
WATTAGE"1/16W"
CDS_SEC"1"
$SEC"1"
ROOM"SMBUS"
BOM_COST"SM_CONTROLLER"
CDS_LIB"mstr_discrete"
CDS_LOCATION"R9G13";
"B"
$PN"2"28;
"A"
$PN"1"26;
%"RES"
"1","(-2875,2525)","0","mstr_discrete","I228";
;
MATERIAL"CHIP"
LOCATION"R8G5"
PART_NUMBER"G21796-173"
WATTAGE"1/16W"
VALUE"20.0"
TOLERANCE"1%"
PACK_TYPE"0402"
BOM_COST"SM_CONTROLLER"
CDS_SEC"1"
$SEC"1"
CDS_LOCATION"R8G5"
ROOM"SMBUS"
CDS_LIB"mstr_discrete";
"B"
$PN"2"31;
"A"
$PN"1"12;
%"RES"
"1","(-2875,2350)","0","mstr_discrete","I229";
;
MATERIAL"CHIP"
TOLERANCE"1%"
LOCATION"R8G4"
PART_NUMBER"G21796-173"
WATTAGE"1/16W"
VALUE"20.0"
PACK_TYPE"0402"
CDS_SEC"1"
$SEC"1"
BOM_COST"SM_CONTROLLER"
ROOM"SMBUS"
CDS_LIB"mstr_discrete"
CDS_LOCATION"R8G4";
"B"
$PN"2"25;
"A"
$PN"1"13;
%"RES"
"1","(-3175,3600)","0","mstr_discrete","I230";
;
TOLERANCE"1%"
MATERIAL"CHIP"
VALUE"20.0"
PART_NUMBER"G21796-173"
PACK_TYPE"0402"
WATTAGE"1/16W"
LOCATION"R2U34"
CDS_SEC"1"
CDS_LIB"mstr_discrete"
BOM_COST"SM_CONTROLLER"
$SEC"1"
CDS_LOCATION"R2U34"
ROOM"SMBUS";
"B"
$PN"2"21;
"A"
$PN"1"34;
%"RES"
"1","(-3175,3775)","0","mstr_discrete","I231";
;
TOLERANCE"1%"
MATERIAL"CHIP"
PACK_TYPE"0402"
WATTAGE"1/16W"
LOCATION"R2U33"
PART_NUMBER"G21796-173"
VALUE"20.0"
BOM_COST"SM_CONTROLLER"
CDS_SEC"1"
$SEC"1"
ROOM"SMBUS"
CDS_LOCATION"R2U33"
CDS_LIB"mstr_discrete";
"B"
$PN"2"20;
"A"
$PN"1"33;
%"RES"
"1","(-3175,4775)","0","mstr_discrete","I232";
;
PACK_TYPE"0402"
VALUE"20.0"
WATTAGE"1/16W"
TOLERANCE"1%"
PART_NUMBER"G21796-173"
MATERIAL"CHIP"
LOCATION"R1U9"
ROOM"SMBUS"
CDS_LOCATION"R1U9"
CDS_LIB"mstr_discrete"
BOM_COST"SM_CONTROLLER"
$SEC"1"
CDS_SEC"1";
"B"
$PN"2"7;
"A"
$PN"1"35;
%"RES"
"1","(-3175,4950)","0","mstr_discrete","I233";
;
WATTAGE"1/16W"
LOCATION"R1U10"
MATERIAL"CHIP"
TOLERANCE"1%"
VALUE"20.0"
PACK_TYPE"0402"
PART_NUMBER"G21796-173"
CDS_LOCATION"R1U10"
BOM_COST"SM_CONTROLLER"
ROOM"SMBUS"
CDS_LIB"mstr_discrete"
$SEC"1"
CDS_SEC"1";
"B"
$PN"2"32;
"A"
$PN"1"36;
%"P3V3_STBY"
"1","(-3500,4325)","0","mstr_symbols","I234";
;
VOLTAGE"3.3V"
CDS_LIB"mstr_symbols"
SIZE"1B"
BODY_TYPE"PLUMBING"
HDL_POWER"P3V3_STBY";
"G\NAC"5;
%"RES"
"2","(-3500,4100)","0","mstr_discrete","I235";
;
PACK_TYPE"0402"
TOLERANCE"1%"
MATERIAL"CHIP"
PART_NUMBER"G21796-001"
WATTAGE"1/16W"
LOCATION"R8C15"
VALUE"2.0K"
CDS_LIB"mstr_discrete"
ROOM"SMBUS"
BOM_COST"SM_CONTROLLER"
CDS_LOCATION"R8C15"
SEC_TYPE"0402"
SEC"1"
CDS_SEC"1";
"A"
$PN"1"5;
"B"
$PN"2"34;
%"P3V3_STBY"
"1","(-3900,4375)","0","mstr_symbols","I236";
;
VOLTAGE"3.3V"
CDS_LIB"mstr_symbols"
SIZE"1B"
BODY_TYPE"PLUMBING"
HDL_POWER"P3V3_STBY";
"G\NAC"6;
%"RES"
"2","(-3900,4150)","0","mstr_discrete","I237";
;
MATERIAL"CHIP"
TOLERANCE"1%"
VALUE"2.0K"
LOCATION"R8C16"
PACK_TYPE"0402"
PART_NUMBER"G21796-001"
WATTAGE"1/16W"
CDS_LIB"mstr_discrete"
ROOM"SMBUS"
CDS_LOCATION"R8C16"
BOM_COST"SM_CONTROLLER"
SEC_TYPE"0402"
SEC"1"
CDS_SEC"1";
"A"
$PN"1"6;
"B"
$PN"2"33;
END.
